# SCM (Grand Teton) — schematic netlist excerpt (pin names and nets, part order shuffled) for the footprints in the layout excerpt that follows; sources: Cadence DE-HDL packaged netlist, KiCad conversion of 12092022_DA0F0TMDCD0_F0T_Management_Board_D_brd_V3_OCP.brd

C63  Q_CAP  2200PF 50V 10% X7R  pkg 0402  page 16 : A = P1V2_STBY_MVDD_CK ; B = GND
R1  Q_RES  0 5% EMPTY  pkg 0402LF  page 20 : A = M_BMC_DDR4_BG1 ; B = M_BMC_DDR4_MBG1

(kicad_pcb
	(version 20260206)
	(generator "pcbnew")
	(generator_version "10.0")
	(general
		(thickness 1.6)
		(legacy_teardrops no)
	)
	(paper "A4")
	(title_block
		(title "12092022_DA0F0TMDCD0_F0T_Management_Board_D_brd_V3_OCP.brd")
		(comment 1 "Grand Teton / footprints 1051-1052 of 1440")
	)
	(layers
		(0 "F.Cu" signal "TOP")
		(4 "In1.Cu" signal "GND")
		(6 "In2.Cu" signal "IN1")
		(8 "In3.Cu" signal "GND1")
		(10 "In4.Cu" signal "IN2")
		(12 "In5.Cu" signal "VCC")
		(14 "In6.Cu" signal "VCC1")
		(16 "In7.Cu" signal "IN3")
		(18 "In8.Cu" signal "GND2")
		(20 "In9.Cu" signal "IN4")
		(22 "In10.Cu" signal "GND3")
		(2 "B.Cu" signal "BOTTOM")
		(9 "F.Adhes" user "F.Adhesive")
		(11 "B.Adhes" user "B.Adhesive")
		(13 "F.Paste" user "Package Geometry/Pastemask Top")
		(15 "B.Paste" user "Package Geometry/Pastemask Bottom")
		(5 "F.SilkS" user "Ref Des/Silkscreen Top")
		(7 "B.SilkS" user "Ref Des/Silkscreen Bottom")
		(1 "F.Mask" user "Board Geometry/Soldermask Top")
		(3 "B.Mask" user "Board Geometry/Soldermask Bottom")
		(17 "Dwgs.User" user "User.Drawings")
		(19 "Cmts.User" user "User.Comments")
		(21 "Eco1.User" user "User.Eco1")
		(23 "Eco2.User" user "User.Eco2")
		(25 "Edge.Cuts" user "Board Geometry/Outline")
		(27 "Margin" user)
		(31 "F.CrtYd" user "Package Geometry/Place Bound Top")
		(29 "B.CrtYd" user "Package Geometry/Place Bound Bottom")
		(35 "F.Fab" user "Ref Des/Assembly Top")
		(33 "B.Fab" user "Ref Des/Assembly Bottom")
	)
	(footprint ""
		(layer "B.Cu")
		(at 83.16722 -46.586394)
		(property "Reference" "R1"
			(at 0 0 0)
			(layer "B.SilkS")
			(hide yes)
			(effects
				(font
					(size 1.27 1.27)
				)
				(justify mirror)
			)
		)
		(property "Value" ""
			(at 0 0 0)
			(layer "B.Fab")
			(effects
				(font
					(size 1.27 1.27)
				)
				(justify mirror)
			)
		)
		(duplicate_pad_numbers_are_jumpers no)
		(fp_line
			(start -0.7874 -0.4064)
			(end -0.7874 0.4064)
			(stroke
				(width 0.1524)
				(type default)
			)
			(layer "B.SilkS")
		)
		(fp_line
			(start -0.7874 0.4064)
			(end 0.7874 0.4064)
			(stroke
				(width 0.1524)
				(type default)
			)
			(layer "B.SilkS")
		)
		(fp_line
			(start 0.7874 -0.4064)
			(end -0.7874 -0.4064)
			(stroke
				(width 0.1524)
				(type default)
			)
			(layer "B.SilkS")
		)
		(fp_line
			(start 0.7874 0.4064)
			(end 0.7874 -0.4064)
			(stroke
				(width 0.1524)
				(type default)
			)
			(layer "B.SilkS")
		)
		(fp_line
			(start -0.67945 -0.3048)
			(end -0.67945 0.3048)
			(stroke
				(width 0.1)
				(type default)
			)
			(layer "B.Fab")
		)
		(fp_line
			(start -0.67945 0.3048)
			(end -0.120396 0.3048)
			(stroke
				(width 0.1)
				(type default)
			)
			(layer "B.Fab")
		)
		(fp_line
			(start -0.12065 -0.3048)
			(end -0.67945 -0.3048)
			(stroke
				(width 0.1)
				(type default)
			)
			(layer "B.Fab")
		)
		(fp_line
			(start -0.12065 -0.2794)
			(end -0.12065 -0.3048)
			(stroke
				(width 0.1)
				(type default)
			)
			(layer "B.Fab")
		)
		(fp_line
			(start -0.120396 0.2794)
			(end 0.12065 0.2794)
			(stroke
				(width 0.1)
				(type default)
			)
			(layer "B.Fab")
		)
		(fp_line
			(start -0.120396 0.3048)
			(end -0.120396 0.2794)
			(stroke
				(width 0.1)
				(type default)
			)
			(layer "B.Fab")
		)
		(fp_line
			(start 0.12065 -0.305054)
			(end 0.12065 -0.2794)
			(stroke
				(width 0.1)
				(type default)
			)
			(layer "B.Fab")
		)
		(fp_line
			(start 0.12065 -0.2794)
			(end -0.12065 -0.2794)
			(stroke
				(width 0.1)
				(type default)
			)
			(layer "B.Fab")
		)
		(fp_line
			(start 0.12065 0.2794)
			(end 0.12065 0.3048)
			(stroke
				(width 0.1)
				(type default)
			)
			(layer "B.Fab")
		)
		(fp_line
			(start 0.12065 0.3048)
			(end 0.67945 0.3048)
			(stroke
				(width 0.1)
				(type default)
			)
			(layer "B.Fab")
		)
		(fp_line
			(start 0.67945 -0.305054)
			(end 0.12065 -0.305054)
			(stroke
				(width 0.1)
				(type default)
			)
			(layer "B.Fab")
		)
		(fp_line
			(start 0.67945 0.3048)
			(end 0.67945 -0.305054)
			(stroke
				(width 0.1)
				(type default)
			)
			(layer "B.Fab")
		)
		(pad "1" smd circle
			(at 0.40005 0 180)
			(size 0 0)
			(layers "B.Cu" "B.Mask" "B.Paste")
			(net "M_BMC_DDR4_BG1")
		)
		(pad "2" smd circle
			(at -0.40005 0 180)
			(size 0 0)
			(layers "B.Cu" "B.Mask" "B.Paste")
			(net "M_BMC_DDR4_MBG1")
		)
	)
	(footprint ""
		(layer "B.Cu")
		(at 68.299838 -40.87622 90)
		(property "Reference" "C63"
			(at 0 0 90)
			(layer "B.SilkS")
			(hide yes)
			(effects
				(font
					(size 1.27 1.27)
				)
				(justify mirror)
			)
		)
		(property "Value" ""
			(at 0 0 90)
			(layer "B.Fab")
			(effects
				(font
					(size 1.27 1.27)
				)
				(justify mirror)
			)
		)
		(duplicate_pad_numbers_are_jumpers no)
		(fp_line
			(start 0.7874 -0.4064)
			(end -0.7874 -0.4064)
			(stroke
				(width 0.1524)
				(type default)
			)
			(layer "B.SilkS")
		)
		(fp_line
			(start -0.7874 -0.4064)
			(end -0.7874 0.4064)
			(stroke
				(width 0.1524)
				(type default)
			)
			(layer "B.SilkS")
		)
		(fp_line
			(start 0.7874 0.4064)
			(end 0.7874 -0.4064)
			(stroke
				(width 0.1524)
				(type default)
			)
			(layer "B.SilkS")
		)
		(fp_line
			(start -0.7874 0.4064)
			(end 0.7874 0.4064)
			(stroke
				(width 0.1524)
				(type default)
			)
			(layer "B.SilkS")
		)
		(fp_line
			(start 0.67945 -0.305054)
			(end 0.12065 -0.305054)
			(stroke
				(width 0.1)
				(type default)
			)
			(layer "B.Fab")
		)
		(fp_line
			(start 0.12065 -0.305054)
			(end 0.12065 -0.2794)
			(stroke
				(width 0.1)
				(type default)
			)
			(layer "B.Fab")
		)
		(fp_line
			(start -0.12065 -0.3048)
			(end -0.67945 -0.3048)
			(stroke
				(width 0.1)
				(type default)
			)
			(layer "B.Fab")
		)
		(fp_line
			(start -0.67945 -0.3048)
			(end -0.67945 0.3048)
			(stroke
				(width 0.1)
				(type default)
			)
			(layer "B.Fab")
		)
		(fp_line
			(start 0.12065 -0.2794)
			(end -0.12065 -0.2794)
			(stroke
				(width 0.1)
				(type default)
			)
			(layer "B.Fab")
		)
		(fp_line
			(start -0.12065 -0.2794)
			(end -0.12065 -0.3048)
			(stroke
				(width 0.1)
				(type default)
			)
			(layer "B.Fab")
		)
		(fp_line
			(start 0.12065 0.2794)
			(end 0.12065 0.3048)
			(stroke
				(width 0.1)
				(type default)
			)
			(layer "B.Fab")
		)
		(fp_line
			(start -0.120396 0.2794)
			(end 0.12065 0.2794)
			(stroke
				(width 0.1)
				(type default)
			)
			(layer "B.Fab")
		)
		(fp_line
			(start 0.67945 0.3048)
			(end 0.67945 -0.305054)
			(stroke
				(width 0.1)
				(type default)
			)
			(layer "B.Fab")
		)
		(fp_line
			(start 0.12065 0.3048)
			(end 0.67945 0.3048)
			(stroke
				(width 0.1)
				(type default)
			)
			(layer "B.Fab")
		)
		(fp_line
			(start -0.120396 0.3048)
			(end -0.120396 0.2794)
			(stroke
				(width 0.1)
				(type default)
			)
			(layer "B.Fab")
		)
		(fp_line
			(start -0.67945 0.3048)
			(end -0.120396 0.3048)
			(stroke
				(width 0.1)
				(type default)
			)
			(layer "B.Fab")
		)
		(pad "1" smd circle
			(at 0.40005 0 270)
			(size 0 0)
			(layers "B.Cu" "B.Mask" "B.Paste")
			(net "P1V2_STBY_MVDD_CK")
		)
		(pad "2" smd circle
			(at -0.40005 0 270)
			(size 0 0)
			(layers "B.Cu" "B.Mask" "B.Paste")
			(net "GND")
		)
	)
)
